Altium Designer Pick and Place Locations
C:\Users\<user>\Desktop\WorkNotes\Projects\PTP\Time-Appliance-Project-master\Time-Card\GNSS\UBlox\M2-ZED-F9T\ECAD\Project Outputs for M2_ZED-F9T_MODULE\Pick Place for M2_ZED-F9T_MODULE(845-XXXXX_PCBA_projectname).txt

========================================================================================================================
File Design Information:

Date:       01/07/23
Time:       12:20
Revision:   Not in VersionControl
Variant:    845-XXXXX_PCBA_projectname
Units used: mil

Designator Comment           Layer    Footprint                      Center-X(mil) Center-Y(mil) Rotation Description                                                                                 
D3         LTST-C191KGKT     TopLayer FP-LTST-C191KGKT-MFG           99.915        461.922       0        "LED GREEN CLEAR SMD"                                                                       
D2         LTST-C191KGKT     TopLayer FP-LTST-C191KGKT-MFG           724.409       381.890       0        "LED GREEN CLEAR SMD"                                                                       
U1         ZED-F9T-00B       TopLayer GPS_ZED-F9T                    435.039       972.835       180      "Multi-band GNSS Receiver with Nanosecond-level Timing Accuracy"                            
U4         LPV511MGX/NOPB    TopLayer DCK0005A_N                     200.787       1561.929      90       "micropower Rail-to-Rail Input and Output Operational Amplifier, 5-pin SC-70, Pb-Free"      
U3         SN74LVC3G07DCUR   TopLayer DCU0008A_N                     82.677        1480.315      270      "Triple Buffer/Driver With Open-Drain Output, DCU0008A, LARGE T&R"                          
R18        1k                TopLayer FP-RMCF0402-MFG                43.307        1354.331      270      "1kO ±1% 0.063W 0402 Thick Film Chip Resistor AEC-Q200 compliant"                           
R17        1k                TopLayer FP-RMCF0402-MFG                102.362       1354.331      270      "1kO ±1% 0.063W 0402 Thick Film Chip Resistor AEC-Q200 compliant"                           
P1         U.FL-R-SMT-1(01)  TopLayer HRS-U.FL-R-SMT-3_V             674.423       1562.989      0        "Ultra Small Coaxial Connector, 6 GHz, -40 to 90 degC, 3-Pin SMD, RoHS, Bulk"               
D1         PESD0402-140      TopLayer FP-PESD0402-MFG                698.995       1478.892      180      "TVS DIODE 14V 40V 0402"                                                                    
C12        10nF              TopLayer FP-GRM033-0_03-IPC_B           598.274       1421.324      270      "Chip Multilayer Ceramic Capacitors for General Purpose, 0201, 10000pF, X7R, 15%, 10%, 16V" 
C11        100nF             TopLayer FP-0402-L_1_0_0_05-W_0_5-IPC_B 157.480       1377.953      270      None                                                                                        
C10        100nF             TopLayer FP-0402-L_1_0_0_05-W_0_5-IPC_B 673.228       1374.016      90       None                                                                                        
C9         100nF             TopLayer FP-0402-L_1_0_0_05-W_0_5-IPC_B 106.299       1614.173      180      None                                                                                        
R16        "22_1%_1218 1.5W" TopLayer FP-CRCW1218-HPe3-MFG           472.441       1425.197      270      "RES Thick Film, 22.6O, 1%, 1.5W, 100ppm/°C, 1218"                                          
R15        0_5%_0402         TopLayer RESC1005X40X25NL05T10          409.449       307.087       90       ""                                                                                          
R14        DNI_0_5%_0402     TopLayer RESC1005X40X25NL05T10          448.819       307.087       90       ""                                                                                          
R13        0_5%_0402         TopLayer RESC1005X40X25NL05T10          318.898       318.898       270      ""                                                                                          
R12        0_5%_0402         TopLayer RESC1005X40X25NL05T10          271.654       318.898       270      ""                                                                                          
R11        100k              TopLayer FP-RMCF0402-IPC_C              248.031       1469.441      0        "100kO ±1% 0.063W 0402 Thick Film Chip Resistor AEC-Q200 compliant"                         
R2         0_5%_0402         TopLayer RESC1005X40X25NL05T10          311.024       440.945       180      ""                                                                                          
C7         47uF_6.3V_1206    TopLayer FP-GRM31C-0_2-e0_3_0_8-IPC_C   98.425        267.716       180      "Chip Multilayer Ceramic Capacitors for General Purpose, 1206, 47uF, X5R, 15%, 20%, 6.3V"   
C6         47uF_6.3V_1206    TopLayer FP-GRM31C-0_2-e0_3_0_8-IPC_C   795.276       251.969       90       "Chip Multilayer Ceramic Capacitors for General Purpose, 1206, 47uF, X5R, 15%, 20%, 6.3V"   
R9         100k              TopLayer FP-RMCF0402-IPC_C              212.598       1401.575      270      "100kO ±1% 0.063W 0402 Thick Film Chip Resistor AEC-Q200 compliant"                         
R7         1k                TopLayer FP-RMCF0402-MFG                106.299       515.748       180      "1kO ±1% 0.063W 0402 Thick Film Chip Resistor AEC-Q200 compliant"                           
Q1         NTR2101PT1G       TopLayer ONSC-SOT-23-3-318-08_V         299.213       1385.827      0        "Small Signal MOSFET, -8 V, -3.7 A, Single P-Channel, 3-Pin SOT-23, Pb-Free, Tape and Reel" 
C5         1uF_25V_0402      TopLayer FP-CL542-IPC_C                 251.969       500.000       0        "Cap Ceramic 1uF 25V X5R ±10% SMD 0402 +85°C Paper T/R"                                     
R10        1k                TopLayer FP-RMCF0402-MFG                322.835       1469.488      0        "1kO ±1% 0.063W 0402 Thick Film Chip Resistor AEC-Q200 compliant"                           
R4         1k                TopLayer FP-RMCF0402-MFG                629.921       381.890       0        "1kO ±1% 0.063W 0402 Thick Film Chip Resistor AEC-Q200 compliant"                           
R3         0_5%_0402         TopLayer RESC1005X40X25NL05T10          311.024       397.638       180      ""                                                                                          
R1         1k                TopLayer FP-RMCF0402-MFG                251.969       551.181       180      "1kO ±1% 0.063W 0402 Thick Film Chip Resistor AEC-Q200 compliant"                           
L1         "47nH 300mA"      TopLayer FP-LQG15HH_02-IPC_B            657.001       1436.139      0        "Multilayer type RF Inductor 47nH ±5% 0.72O 300mA 0402"                                     
J1         OCPTAP_M2_FINGERS TopLayer OCPTAP_M2_FINGERS              433.071       55.118        0        ""                                                                                          
C4         1uF_25V_0402      TopLayer FP-CL542-IPC_C                 519.685       570.866       0        "Cap Ceramic 1uF 25V X5R ±10% SMD 0402 +85°C Paper T/R"                                     
C3         1uF_25V_0402      TopLayer FP-CL542-IPC_C                 519.685       610.236       0        "Cap Ceramic 1uF 25V X5R ±10% SMD 0402 +85°C Paper T/R"                                     
C2         1uF_25V_0402      TopLayer FP-CL542-IPC_C                 433.071       610.236       0        "Cap Ceramic 1uF 25V X5R ±10% SMD 0402 +85°C Paper T/R"                                     
C1         1uF_25V_0402      TopLayer FP-CL542-IPC_C                 346.546       611.126       180      "Cap Ceramic 1uF 25V X5R ±10% SMD 0402 +85°C Paper T/R"                                     
